(kicad_pcb
	(version 20241229)
	(generator "pcbnew")
	(generator_version "9.0")
	(general
		(thickness 1.599998)
		(legacy_teardrops no)
	)
	(paper "A4")
	(title_block
		(date "2023-02-12")
		(rev "1.1.5")
		(comment 9 "footprints 351-357 of 473")
	)
	(layers
		(0 "F.Cu" signal)
		(4 "In1.Cu" power "In1.GND")
		(6 "In2.Cu" signal)
		(8 "In3.Cu" power "In3.GND")
		(10 "In4.Cu" power "In4.VCC")
		(12 "In5.Cu" signal)
		(14 "In6.Cu" power "In6.VCC")
		(2 "B.Cu" signal)
		(9 "F.Adhes" user "F.Adhesive")
		(11 "B.Adhes" user "B.Adhesive")
		(13 "F.Paste" user)
		(15 "B.Paste" user)
		(5 "F.SilkS" user "F.Silkscreen")
		(7 "B.SilkS" user "B.Silkscreen")
		(1 "F.Mask" user)
		(3 "B.Mask" user)
		(17 "Dwgs.User" user "User.Drawings")
		(19 "Cmts.User" user "User.Comments")
		(21 "Eco1.User" user "User.Eco1")
		(23 "Eco2.User" user "User.Eco2")
		(25 "Edge.Cuts" user)
		(27 "Margin" user)
		(31 "F.CrtYd" user "F.Courtyard")
		(29 "B.CrtYd" user "B.Courtyard")
		(35 "F.Fab" user)
		(33 "B.Fab" user)
	)
	(footprint "antmicro-footprints:C_0201"
		(layer "B.Cu")
		(at 171.036328 98.297157)
		(descr "Capacitor SMD 0201")
		(tags "capacitor SMD 0201")
		(property "Reference" "C44"
			(at 1.163672 -0.297157 180)
			(layer "B.SilkS")
			(effects
				(font
					(size 0.7 0.7)
					(thickness 0.15)
				)
				(justify left bottom mirror)
			)
		)
		(property "Value" "C_100n_0201"
			(at 0 -1.4 180)
			(layer "B.Fab")
			(effects
				(font
					(size 0.7 0.7)
					(thickness 0.15)
				)
				(justify left bottom mirror)
			)
		)
		(property "Description" " "
			(at 0 0 0)
			(layer "F.Fab")
			(hide yes)
			(effects
				(font
					(size 1.27 1.27)
					(thickness 0.15)
				)
			)
		)
		(property "Author" "Antmicro"
			(at 0 0 0)
			(layer "B.Fab")
			(hide yes)
			(effects
				(font
					(size 1 1)
					(thickness 0.15)
				)
				(justify mirror)
			)
		)
		(property "Dielectric" ""
			(at 0 0 0)
			(layer "B.Fab")
			(hide yes)
			(effects
				(font
					(size 1 1)
					(thickness 0.15)
				)
				(justify mirror)
			)
		)
		(property "License" "Apache-2.0"
			(at 0 0 0)
			(layer "B.Fab")
			(hide yes)
			(effects
				(font
					(size 1 1)
					(thickness 0.15)
				)
				(justify mirror)
			)
		)
		(property "MPN" "CC0201KRX6S5BB104"
			(at 0 0 0)
			(layer "B.Fab")
			(hide yes)
			(effects
				(font
					(size 1 1)
					(thickness 0.15)
				)
				(justify mirror)
			)
		)
		(property "Manufacturer" "Yaego"
			(at 0 0 0)
			(layer "B.Fab")
			(hide yes)
			(effects
				(font
					(size 1 1)
					(thickness 0.15)
				)
				(justify mirror)
			)
		)
		(property "Val" "100n"
			(at 0 0 0)
			(layer "B.Fab")
			(hide yes)
			(effects
				(font
					(size 1 1)
					(thickness 0.15)
				)
				(justify mirror)
			)
		)
		(property "Voltage" ""
			(at 0 0 0)
			(layer "B.Fab")
			(hide yes)
			(effects
				(font
					(size 1 1)
					(thickness 0.15)
				)
				(justify mirror)
			)
		)
		(sheetname "FPGA power")
		(sheetfile "fpga-power.kicad_sch")
		(attr smd)
		(fp_rect
			(start -0.72 0.38)
			(end 0.72 -0.38)
			(stroke
				(width 0.05)
				(type solid)
			)
			(fill no)
			(layer "B.CrtYd")
		)
		(fp_rect
			(start 0.3 -0.15)
			(end -0.301 0.149)
			(stroke
				(width 0.15)
				(type solid)
			)
			(fill no)
			(layer "B.Fab")
		)
		(pad "" smd roundrect
			(at -0.349 0.002)
			(size 0.318 0.36)
			(layers "B.Paste")
			(roundrect_rratio 0.25)
		)
		(pad "" smd roundrect
			(at 0.341 0.002)
			(size 0.318 0.36)
			(layers "B.Paste")
			(roundrect_rratio 0.25)
		)
		(pad "1" smd roundrect
			(at -0.321 0.002)
			(size 0.46 0.4)
			(layers "B.Cu" "B.Mask")
			(roundrect_rratio 0.25)
			(net 465 "1V0_SYS")
			(pintype "passive")
		)
		(pad "2" smd roundrect
			(at 0.32 0.002)
			(size 0.46 0.4)
			(layers "B.Cu" "B.Mask")
			(roundrect_rratio 0.25)
			(net 5 "GND")
			(pintype "passive")
		)
	)
	(footprint "antmicro-footprints:C_0201"
		(layer "B.Cu")
		(at 169.411328 99.497157 90)
		(descr "Capacitor SMD 0201")
		(tags "capacitor SMD 0201")
		(property "Reference" "C52"
			(at 1.097157 1.088672 270)
			(layer "B.SilkS")
			(effects
				(font
					(size 0.7 0.7)
					(thickness 0.15)
				)
				(justify left bottom mirror)
			)
		)
		(property "Value" "C_100n_0201"
			(at 0 -1.4 270)
			(layer "B.Fab")
			(effects
				(font
					(size 0.7 0.7)
					(thickness 0.15)
				)
				(justify left bottom mirror)
			)
		)
		(property "Description" " "
			(at 0 0 90)
			(layer "F.Fab")
			(hide yes)
			(effects
				(font
					(size 1.27 1.27)
					(thickness 0.15)
				)
			)
		)
		(property "Author" "Antmicro"
			(at 268.908485 -69.914171 0)
			(layer "B.Fab")
			(hide yes)
			(effects
				(font
					(size 1 1)
					(thickness 0.15)
				)
				(justify mirror)
			)
		)
		(property "Dielectric" ""
			(at 268.908485 -69.914171 0)
			(layer "B.Fab")
			(hide yes)
			(effects
				(font
					(size 1 1)
					(thickness 0.15)
				)
				(justify mirror)
			)
		)
		(property "License" "Apache-2.0"
			(at 268.908485 -69.914171 0)
			(layer "B.Fab")
			(hide yes)
			(effects
				(font
					(size 1 1)
					(thickness 0.15)
				)
				(justify mirror)
			)
		)
		(property "MPN" "CC0201KRX6S5BB104"
			(at 268.908485 -69.914171 0)
			(layer "B.Fab")
			(hide yes)
			(effects
				(font
					(size 1 1)
					(thickness 0.15)
				)
				(justify mirror)
			)
		)
		(property "Manufacturer" "Yaego"
			(at 268.908485 -69.914171 0)
			(layer "B.Fab")
			(hide yes)
			(effects
				(font
					(size 1 1)
					(thickness 0.15)
				)
				(justify mirror)
			)
		)
		(property "Val" "100n"
			(at 268.908485 -69.914171 0)
			(layer "B.Fab")
			(hide yes)
			(effects
				(font
					(size 1 1)
					(thickness 0.15)
				)
				(justify mirror)
			)
		)
		(property "Voltage" ""
			(at 268.908485 -69.914171 0)
			(layer "B.Fab")
			(hide yes)
			(effects
				(font
					(size 1 1)
					(thickness 0.15)
				)
				(justify mirror)
			)
		)
		(sheetname "FPGA power")
		(sheetfile "fpga-power.kicad_sch")
		(attr smd)
		(fp_rect
			(start -0.72 0.38)
			(end 0.72 -0.38)
			(stroke
				(width 0.05)
				(type solid)
			)
			(fill no)
			(layer "B.CrtYd")
		)
		(fp_rect
			(start 0.3 -0.15)
			(end -0.301 0.149)
			(stroke
				(width 0.15)
				(type solid)
			)
			(fill no)
			(layer "B.Fab")
		)
		(pad "" smd roundrect
			(at -0.349 0.002 90)
			(size 0.318 0.36)
			(layers "B.Paste")
			(roundrect_rratio 0.25)
		)
		(pad "" smd roundrect
			(at 0.341 0.002 90)
			(size 0.318 0.36)
			(layers "B.Paste")
			(roundrect_rratio 0.25)
		)
		(pad "1" smd roundrect
			(at -0.321 0.002 90)
			(size 0.46 0.4)
			(layers "B.Cu" "B.Mask")
			(roundrect_rratio 0.25)
			(net 465 "1V0_SYS")
			(pintype "passive")
		)
		(pad "2" smd roundrect
			(at 0.32 0.002 90)
			(size 0.46 0.4)
			(layers "B.Cu" "B.Mask")
			(roundrect_rratio 0.25)
			(net 5 "GND")
			(pintype "passive")
		)
	)
	(footprint "antmicro-footprints:C_0402_1005Metric"
		(layer "B.Cu")
		(at 167.5 95.875)
		(descr "Capacitor SMD 0402")
		(tags "capacitor SMD 0402")
		(property "Reference" "C26"
			(at 1.1 1.225 180)
			(layer "B.SilkS")
			(effects
				(font
					(size 0.7 0.7)
					(thickness 0.15)
				)
				(justify left bottom mirror)
			)
		)
		(property "Value" "C_4u7_0402"
			(at 0 -1.4 180)
			(layer "B.Fab")
			(effects
				(font
					(size 0.7 0.7)
					(thickness 0.15)
				)
				(justify left bottom mirror)
			)
		)
		(property "Description" " "
			(at 0 0 0)
			(layer "F.Fab")
			(hide yes)
			(effects
				(font
					(size 1.27 1.27)
					(thickness 0.15)
				)
			)
		)
		(property "Author" "Antmicro"
			(at 0 0 0)
			(layer "B.Fab")
			(hide yes)
			(effects
				(font
					(size 1 1)
					(thickness 0.15)
				)
				(justify mirror)
			)
		)
		(property "Dielectric" ""
			(at 0 0 0)
			(layer "B.Fab")
			(hide yes)
			(effects
				(font
					(size 1 1)
					(thickness 0.15)
				)
				(justify mirror)
			)
		)
		(property "License" "Apache-2.0"
			(at 0 0 0)
			(layer "B.Fab")
			(hide yes)
			(effects
				(font
					(size 1 1)
					(thickness 0.15)
				)
				(justify mirror)
			)
		)
		(property "MPN" "GRM155R61A475MEAAD"
			(at 0 0 0)
			(layer "B.Fab")
			(hide yes)
			(effects
				(font
					(size 1 1)
					(thickness 0.15)
				)
				(justify mirror)
			)
		)
		(property "Manufacturer" "Murata"
			(at 0 0 0)
			(layer "B.Fab")
			(hide yes)
			(effects
				(font
					(size 1 1)
					(thickness 0.15)
				)
				(justify mirror)
			)
		)
		(property "Val" "4u7"
			(at 0 0 0)
			(layer "B.Fab")
			(hide yes)
			(effects
				(font
					(size 1 1)
					(thickness 0.15)
				)
				(justify mirror)
			)
		)
		(property "Voltage" ""
			(at 0 0 0)
			(layer "B.Fab")
			(hide yes)
			(effects
				(font
					(size 1 1)
					(thickness 0.15)
				)
				(justify mirror)
			)
		)
		(sheetname "FPGA power")
		(sheetfile "fpga-power.kicad_sch")
		(attr smd)
		(fp_rect
			(start -0.94 0.47)
			(end 0.94 -0.47)
			(stroke
				(width 0.05)
				(type solid)
			)
			(fill no)
			(layer "B.CrtYd")
		)
		(fp_rect
			(start -0.499 0.249)
			(end 0.499 -0.249)
			(stroke
				(width 0.15)
				(type solid)
			)
			(fill no)
			(layer "B.Fab")
		)
		(pad "1" smd roundrect
			(at -0.484 0)
			(size 0.59 0.64)
			(layers "B.Cu" "B.Mask" "B.Paste")
			(roundrect_rratio 0.25)
			(net 460 "1V8_SYS")
			(pintype "passive")
		)
		(pad "2" smd roundrect
			(at 0.484 0)
			(size 0.59 0.64)
			(layers "B.Cu" "B.Mask" "B.Paste")
			(roundrect_rratio 0.25)
			(net 5 "GND")
			(pintype "passive")
		)
	)
	(footprint "antmicro-footprints:C_0402_1005Metric"
		(layer "B.Cu")
		(at 171.25 94.125)
		(descr "Capacitor SMD 0402")
		(tags "capacitor SMD 0402")
		(property "Reference" "C30"
			(at 2.95 0.175 180)
			(layer "B.SilkS")
			(effects
				(font
					(size 0.7 0.7)
					(thickness 0.15)
				)
				(justify left bottom mirror)
			)
		)
		(property "Value" "C_4u7_0402"
			(at 0 -1.4 180)
			(layer "B.Fab")
			(effects
				(font
					(size 0.7 0.7)
					(thickness 0.15)
				)
				(justify left bottom mirror)
			)
		)
		(property "Description" " "
			(at 0 0 0)
			(layer "F.Fab")
			(hide yes)
			(effects
				(font
					(size 1.27 1.27)
					(thickness 0.15)
				)
			)
		)
		(property "Author" "Antmicro"
			(at 0 0 0)
			(layer "B.Fab")
			(hide yes)
			(effects
				(font
					(size 1 1)
					(thickness 0.15)
				)
				(justify mirror)
			)
		)
		(property "Dielectric" ""
			(at 0 0 0)
			(layer "B.Fab")
			(hide yes)
			(effects
				(font
					(size 1 1)
					(thickness 0.15)
				)
				(justify mirror)
			)
		)
		(property "License" "Apache-2.0"
			(at 0 0 0)
			(layer "B.Fab")
			(hide yes)
			(effects
				(font
					(size 1 1)
					(thickness 0.15)
				)
				(justify mirror)
			)
		)
		(property "MPN" "GRM155R61A475MEAAD"
			(at 0 0 0)
			(layer "B.Fab")
			(hide yes)
			(effects
				(font
					(size 1 1)
					(thickness 0.15)
				)
				(justify mirror)
			)
		)
		(property "Manufacturer" "Murata"
			(at 0 0 0)
			(layer "B.Fab")
			(hide yes)
			(effects
				(font
					(size 1 1)
					(thickness 0.15)
				)
				(justify mirror)
			)
		)
		(property "Val" "4u7"
			(at 0 0 0)
			(layer "B.Fab")
			(hide yes)
			(effects
				(font
					(size 1 1)
					(thickness 0.15)
				)
				(justify mirror)
			)
		)
		(property "Voltage" ""
			(at 0 0 0)
			(layer "B.Fab")
			(hide yes)
			(effects
				(font
					(size 1 1)
					(thickness 0.15)
				)
				(justify mirror)
			)
		)
		(sheetname "FPGA power")
		(sheetfile "fpga-power.kicad_sch")
		(attr smd)
		(fp_rect
			(start -0.94 0.47)
			(end 0.94 -0.47)
			(stroke
				(width 0.05)
				(type solid)
			)
			(fill no)
			(layer "B.CrtYd")
		)
		(fp_rect
			(start -0.499 0.249)
			(end 0.499 -0.249)
			(stroke
				(width 0.15)
				(type solid)
			)
			(fill no)
			(layer "B.Fab")
		)
		(pad "1" smd roundrect
			(at -0.484 0)
			(size 0.59 0.64)
			(layers "B.Cu" "B.Mask" "B.Paste")
			(roundrect_rratio 0.25)
			(net 460 "1V8_SYS")
			(pintype "passive")
		)
		(pad "2" smd roundrect
			(at 0.484 0)
			(size 0.59 0.64)
			(layers "B.Cu" "B.Mask" "B.Paste")
			(roundrect_rratio 0.25)
			(net 5 "GND")
			(pintype "passive")
		)
	)
	(footprint "antmicro-footprints:C_0402_1005Metric"
		(layer "B.Cu")
		(at 164.625 94 180)
		(descr "Capacitor SMD 0402")
		(tags "capacitor SMD 0402")
		(property "Reference" "C34"
			(at 0.725 -0.9 0)
			(layer "B.SilkS")
			(effects
				(font
					(size 0.7 0.7)
					(thickness 0.15)
				)
				(justify left bottom mirror)
			)
		)
		(property "Value" "C_4u7_0402"
			(at 0 -1.4 0)
			(layer "B.Fab")
			(effects
				(font
					(size 0.7 0.7)
					(thickness 0.15)
				)
				(justify left bottom mirror)
			)
		)
		(property "Description" " "
			(at 0 0 180)
			(layer "F.Fab")
			(hide yes)
			(effects
				(font
					(size 1.27 1.27)
					(thickness 0.15)
				)
			)
		)
		(property "Author" "Antmicro"
			(at 329.25 188 0)
			(layer "B.Fab")
			(hide yes)
			(effects
				(font
					(size 1 1)
					(thickness 0.15)
				)
				(justify mirror)
			)
		)
		(property "Dielectric" ""
			(at 329.25 188 0)
			(layer "B.Fab")
			(hide yes)
			(effects
				(font
					(size 1 1)
					(thickness 0.15)
				)
				(justify mirror)
			)
		)
		(property "License" "Apache-2.0"
			(at 329.25 188 0)
			(layer "B.Fab")
			(hide yes)
			(effects
				(font
					(size 1 1)
					(thickness 0.15)
				)
				(justify mirror)
			)
		)
		(property "MPN" "GRM155R61A475MEAAD"
			(at 329.25 188 0)
			(layer "B.Fab")
			(hide yes)
			(effects
				(font
					(size 1 1)
					(thickness 0.15)
				)
				(justify mirror)
			)
		)
		(property "Manufacturer" "Murata"
			(at 329.25 188 0)
			(layer "B.Fab")
			(hide yes)
			(effects
				(font
					(size 1 1)
					(thickness 0.15)
				)
				(justify mirror)
			)
		)
		(property "Val" "4u7"
			(at 329.25 188 0)
			(layer "B.Fab")
			(hide yes)
			(effects
				(font
					(size 1 1)
					(thickness 0.15)
				)
				(justify mirror)
			)
		)
		(property "Voltage" ""
			(at 329.25 188 0)
			(layer "B.Fab")
			(hide yes)
			(effects
				(font
					(size 1 1)
					(thickness 0.15)
				)
				(justify mirror)
			)
		)
		(sheetname "FPGA power")
		(sheetfile "fpga-power.kicad_sch")
		(attr smd)
		(fp_rect
			(start -0.94 0.47)
			(end 0.94 -0.47)
			(stroke
				(width 0.05)
				(type solid)
			)
			(fill no)
			(layer "B.CrtYd")
		)
		(fp_rect
			(start -0.499 0.249)
			(end 0.499 -0.249)
			(stroke
				(width 0.15)
				(type solid)
			)
			(fill no)
			(layer "B.Fab")
		)
		(pad "1" smd roundrect
			(at -0.484 0 180)
			(size 0.59 0.64)
			(layers "B.Cu" "B.Mask" "B.Paste")
			(roundrect_rratio 0.25)
			(net 460 "1V8_SYS")
			(pintype "passive")
		)
		(pad "2" smd roundrect
			(at 0.484 0 180)
			(size 0.59 0.64)
			(layers "B.Cu" "B.Mask" "B.Paste")
			(roundrect_rratio 0.25)
			(net 5 "GND")
			(pintype "passive")
		)
	)
	(footprint "antmicro-footprints:C_0603_1608Metric"
		(layer "B.Cu")
		(at 163.375 95.375 180)
		(descr "Capacitor SMD 0603")
		(tags "capacitor 0603")
		(property "Reference" "C38"
			(at -1.125 -1.325 0)
			(layer "B.SilkS")
			(effects
				(font
					(size 0.7 0.7)
					(thickness 0.15)
				)
				(justify left bottom mirror)
			)
		)
		(property "Value" "C_47u_0603"
			(at 0 -1.6 0)
			(layer "B.Fab")
			(effects
				(font
					(size 0.7 0.7)
					(thickness 0.15)
				)
				(justify left bottom mirror)
			)
		)
		(property "Description" " "
			(at 0 0 180)
			(layer "F.Fab")
			(hide yes)
			(effects
				(font
					(size 1.27 1.27)
					(thickness 0.15)
				)
			)
		)
		(property "Author" "Antmicro"
			(at 326.75 190.75 0)
			(layer "B.Fab")
			(hide yes)
			(effects
				(font
					(size 1 1)
					(thickness 0.15)
				)
				(justify mirror)
			)
		)
		(property "Dielectric" ""
			(at 326.75 190.75 0)
			(layer "B.Fab")
			(hide yes)
			(effects
				(font
					(size 1 1)
					(thickness 0.15)
				)
				(justify mirror)
			)
		)
		(property "License" "Apache-2.0"
			(at 326.75 190.75 0)
			(layer "B.Fab")
			(hide yes)
			(effects
				(font
					(size 1 1)
					(thickness 0.15)
				)
				(justify mirror)
			)
		)
		(property "MPN" "GRM188R60J476ME15D"
			(at 326.75 190.75 0)
			(layer "B.Fab")
			(hide yes)
			(effects
				(font
					(size 1 1)
					(thickness 0.15)
				)
				(justify mirror)
			)
		)
		(property "Manufacturer" "Murata"
			(at 326.75 190.75 0)
			(layer "B.Fab")
			(hide yes)
			(effects
				(font
					(size 1 1)
					(thickness 0.15)
				)
				(justify mirror)
			)
		)
		(property "Val" "47u"
			(at 326.75 190.75 0)
			(layer "B.Fab")
			(hide yes)
			(effects
				(font
					(size 1 1)
					(thickness 0.15)
				)
				(justify mirror)
			)
		)
		(property "Voltage" ""
			(at 326.75 190.75 0)
			(layer "B.Fab")
			(hide yes)
			(effects
				(font
					(size 1 1)
					(thickness 0.15)
				)
				(justify mirror)
			)
		)
		(sheetname "FPGA power")
		(sheetfile "fpga-power.kicad_sch")
		(attr smd)
		(fp_line
			(start -0.3 0.3)
			(end 0.3 0.3)
			(stroke
				(width 0.15)
				(type solid)
			)
			(layer "B.SilkS")
		)
		(fp_line
			(start -0.3 -0.3)
			(end 0.3 -0.3)
			(stroke
				(width 0.15)
				(type solid)
			)
			(layer "B.SilkS")
		)
		(fp_rect
			(start -1.24 0.7)
			(end 1.24 -0.7)
			(stroke
				(width 0.05)
				(type solid)
			)
			(fill no)
			(layer "B.CrtYd")
		)
		(fp_rect
			(start -0.8 0.4)
			(end 0.8 -0.4)
			(stroke
				(width 0.15)
				(type solid)
			)
			(fill no)
			(layer "B.Fab")
		)
		(pad "1" smd roundrect
			(at -0.7 0 180)
			(size 0.6 0.8)
			(layers "B.Cu" "B.Mask" "B.Paste")
			(roundrect_rratio 0.2)
			(net 460 "1V8_SYS")
			(pintype "passive")
		)
		(pad "2" smd roundrect
			(at 0.7 0 180)
			(size 0.6 0.8)
			(layers "B.Cu" "B.Mask" "B.Paste")
			(roundrect_rratio 0.2)
			(net 5 "GND")
			(pintype "passive")
		)
	)
	(footprint "antmicro-footprints:C_0603_1608Metric"
		(layer "B.Cu")
		(at 175.5 97.875)
		(descr "Capacitor SMD 0603")
		(tags "capacitor 0603")
		(property "Reference" "C42"
			(at 3.2 0.325 180)
			(layer "B.SilkS")
			(effects
				(font
					(size 0.7 0.7)
					(thickness 0.15)
				)
				(justify left bottom mirror)
			)
		)
		(property "Value" "C_47u_0603"
			(at 0 -1.6 180)
			(layer "B.Fab")
			(effects
				(font
					(size 0.7 0.7)
					(thickness 0.15)
				)
				(justify left bottom mirror)
			)
		)
		(property "Description" " "
			(at 0 0 0)
			(layer "F.Fab")
			(hide yes)
			(effects
				(font
					(size 1.27 1.27)
					(thickness 0.15)
				)
			)
		)
		(property "Author" "Antmicro"
			(at 0 0 0)
			(layer "B.Fab")
			(hide yes)
			(effects
				(font
					(size 1 1)
					(thickness 0.15)
				)
				(justify mirror)
			)
		)
		(property "Dielectric" ""
			(at 0 0 0)
			(layer "B.Fab")
			(hide yes)
			(effects
				(font
					(size 1 1)
					(thickness 0.15)
				)
				(justify mirror)
			)
		)
		(property "License" "Apache-2.0"
			(at 0 0 0)
			(layer "B.Fab")
			(hide yes)
			(effects
				(font
					(size 1 1)
					(thickness 0.15)
				)
				(justify mirror)
			)
		)
		(property "MPN" "GRM188R60J476ME15D"
			(at 0 0 0)
			(layer "B.Fab")
			(hide yes)
			(effects
				(font
					(size 1 1)
					(thickness 0.15)
				)
				(justify mirror)
			)
		)
		(property "Manufacturer" "Murata"
			(at 0 0 0)
			(layer "B.Fab")
			(hide yes)
			(effects
				(font
					(size 1 1)
					(thickness 0.15)
				)
				(justify mirror)
			)
		)
		(property "Val" "47u"
			(at 0 0 0)
			(layer "B.Fab")
			(hide yes)
			(effects
				(font
					(size 1 1)
					(thickness 0.15)
				)
				(justify mirror)
			)
		)
		(property "Voltage" ""
			(at 0 0 0)
			(layer "B.Fab")
			(hide yes)
			(effects
				(font
					(size 1 1)
					(thickness 0.15)
				)
				(justify mirror)
			)
		)
		(sheetname "FPGA power")
		(sheetfile "fpga-power.kicad_sch")
		(attr smd)
		(fp_line
			(start -0.3 -0.3)
			(end 0.3 -0.3)
			(stroke
				(width 0.15)
				(type solid)
			)
			(layer "B.SilkS")
		)
		(fp_line
			(start -0.3 0.3)
			(end 0.3 0.3)
			(stroke
				(width 0.15)
				(type solid)
			)
			(layer "B.SilkS")
		)
		(fp_rect
			(start -1.24 0.7)
			(end 1.24 -0.7)
			(stroke
				(width 0.05)
				(type solid)
			)
			(fill no)
			(layer "B.CrtYd")
		)
		(fp_rect
			(start -0.8 0.4)
			(end 0.8 -0.4)
			(stroke
				(width 0.15)
				(type solid)
			)
			(fill no)
			(layer "B.Fab")
		)
		(pad "1" smd roundrect
			(at -0.7 0)
			(size 0.6 0.8)
			(layers "B.Cu" "B.Mask" "B.Paste")
			(roundrect_rratio 0.2)
			(net 460 "1V8_SYS")
			(pintype "passive")
		)
		(pad "2" smd roundrect
			(at 0.7 0)
			(size 0.6 0.8)
			(layers "B.Cu" "B.Mask" "B.Paste")
			(roundrect_rratio 0.2)
			(net 5 "GND")
			(pintype "passive")
		)
	)
)
